G04 ================== begin FILE IDENTIFICATION RECORD ==================*
G04 Layout Name:  t6mg_pdb_a_v02_0109_1330.brd*
G04 Film Name:    smb.art*
G04 File Format:  Gerber RS274X*
G04 File Origin:  Cadence Allegro 16.3-S038*
G04 Origin Date:  Mon Jan 13 14:11:51 2014*
G04 *
G04 Layer:  DRAWING FORMAT/TITLE_BLOCK*
G04 Layer:  VIA CLASS/SOLDERMASK_BOTTOM*
G04 Layer:  PIN/SOLDERMASK_BOTTOM*
G04 Layer:  PACKAGE GEOMETRY/SOLDERMASK_BOTTOM*
G04 Layer:  MANUFACTURING/PHOTOPLOT_OUTLINE*
G04 Layer:  DRAWING FORMAT/TITLE_DATA_SMB*
G04 Layer:  BOARD GEOMETRY/SOLDERMASK_BOTTOM*
G04 *
G04 Offset:    (0.00 0.00)*
G04 Mirror:    No*
G04 Mode:      Positive*
G04 Rotation:  0*
G04 FullContactRelief:  No*
G04 UndefLineWidth:     6.00*
G04 ================== end FILE IDENTIFICATION RECORD ====================*
%FSLAX25Y25*MOIN*%
%IR0*IPPOS*OFA0.00000B0.00000*MIA0B0*SFA1.00000B1.00000*%
%ADD21C,.03*%
%ADD33C,.05*%
%ADD25C,.034*%
%ADD15C,.044*%
%ADD19C,.072*%
%ADD18C,.081*%
%ADD13C,.056*%
%ADD32R,.05X.05*%
%ADD11C,.067*%
%ADD29C,.068*%
%ADD23C,.059*%
%ADD17R,.044X.044*%
%ADD22R,.081X.081*%
%ADD20C,.097*%
%ADD27R,.056X.056*%
%ADD12R,.067X.067*%
%ADD30R,.068X.068*%
%ADD24R,.059X.059*%
%ADD38R,.024X.022*%
%ADD39R,.022X.024*%
%ADD35O,.225X.264*%
%ADD16C,.115*%
%ADD10C,.152*%
%ADD34C,.225*%
%ADD37R,.018X.063*%
%ADD28C,.118*%
%ADD36C,.335*%
%ADD31C,.119*%
%ADD14C,.146*%
%ADD26C,.178*%
%ADD40C,.02*%
%ADD41C,.006*%
%ADD42C,.194*%
G75*
%LPD*%
G75*
G36*
G01X65354Y95060D02*
G02I0J19900D01*
G37*
G36*
G01Y445060D02*
G02I0J19900D01*
G37*
G36*
G01Y795060D02*
G02I0J19900D01*
G37*
G36*
G01Y1145060D02*
G02I0J19900D01*
G37*
G36*
G01Y1495060D02*
G02I0J19900D01*
G37*
G36*
G01Y1845060D02*
G02I0J19900D01*
G37*
G36*
G01X61058Y882277D02*
G03I-5900J0D01*
G37*
G36*
G01X326986Y127165D02*
G02I-19900J0D01*
G37*
G36*
G01Y477165D02*
G02I-19900J0D01*
G37*
G36*
G01Y827165D02*
G02I-19900J0D01*
G37*
G36*
G01Y1343504D02*
G02I-19900J0D01*
G37*
G36*
G01Y1693504D02*
G02I-19900J0D01*
G37*
G36*
G01X326987Y2043503D02*
G02I-19900J0D01*
G37*
G36*
G01X350726Y2035270D02*
G03I-5900J0D01*
G37*
G36*
G01X395472Y66182D02*
G03I-5900J0D01*
G37*
%LPC*%
G75*
G54D42*
X65354Y114960D03*
Y464960D03*
Y814960D03*
Y1164960D03*
Y1514960D03*
Y1864960D03*
X307086Y127165D03*
Y477165D03*
Y827165D03*
Y1343504D03*
Y1693504D03*
X307087Y2043503D03*
%LPD*%
G75*
G54D10*
X29979Y30500D03*
Y75500D03*
Y166500D03*
Y211500D03*
Y239500D03*
Y284500D03*
Y375500D03*
Y420500D03*
G54D20*
X45411Y505996D03*
Y568004D03*
Y1564000D03*
Y1626008D03*
G54D11*
X22756Y113818D03*
X22480Y316838D03*
Y328649D03*
X22756Y1866819D03*
Y1948818D03*
Y2023818D03*
G54D30*
X119920Y328071D03*
Y676102D03*
Y1024134D03*
Y1372165D03*
Y1720197D03*
Y2068228D03*
G54D12*
X22756Y125629D03*
X22480Y340460D03*
X22756Y1878630D03*
Y1960629D03*
Y2035629D03*
G54D21*
X49441Y1238962D03*
X45581Y1278420D03*
X45413Y1283724D03*
X45244Y1289067D03*
X45350Y1299697D03*
X45267Y1294203D03*
X45281Y1310893D03*
X45244Y1305787D03*
X46980Y1325843D03*
Y1315843D03*
Y1320843D03*
Y1330843D03*
Y1345843D03*
Y1340843D03*
X61888Y666012D03*
X57124Y675327D03*
X54483Y679810D03*
X59236Y670758D03*
X70865Y872278D03*
Y866278D03*
Y860278D03*
Y897750D03*
Y890116D03*
X61866Y1309190D03*
X54543Y1308995D03*
X67568Y1307829D03*
X61866Y1342104D03*
X95775Y751469D03*
X89338Y878294D03*
X91733Y899382D03*
X92633Y907404D03*
X91294Y926951D03*
X98139Y990959D03*
X82763Y1060051D03*
X96684Y1081791D03*
X96510Y1395382D03*
X106958Y26285D03*
X107405Y49898D03*
X107037Y34687D03*
X106836Y376461D03*
X106709Y391219D03*
X107025Y725368D03*
X106935Y745139D03*
X107173Y735219D03*
X100687Y999391D03*
X107351Y1093484D03*
X107235Y1081791D03*
X107215Y1072208D03*
X105152Y1118381D03*
X100719Y1312810D03*
Y1306810D03*
Y1330810D03*
Y1336810D03*
Y1324810D03*
Y1318810D03*
Y1346065D03*
X106962Y1434041D03*
X106921Y1419492D03*
X106763Y1444599D03*
X107006Y1452651D03*
X107355Y1770437D03*
X107220Y1791589D03*
X107373Y1780544D03*
X106819Y1802230D03*
X144878Y1738861D03*
X157558Y51426D03*
X156865Y401207D03*
X156610Y751063D03*
X156854Y1101031D03*
X158618Y1399448D03*
X164037Y1400226D03*
X170351Y1401324D03*
X159192Y1451105D03*
X163257Y1737619D03*
X150309Y1737009D03*
X168151Y1739208D03*
X165782Y1732903D03*
X156183Y1735240D03*
X156452Y1800821D03*
X175989Y944537D03*
X176011Y936829D03*
X175359Y963486D03*
X175561Y955964D03*
X175135Y972490D03*
X175022Y980281D03*
X175742Y989958D03*
X175449Y997660D03*
X175698Y1008730D03*
X175473Y1016296D03*
X175448Y1031766D03*
X175897Y1023997D03*
X176083Y1402321D03*
X173394Y1736051D03*
X256947Y128276D03*
X257125Y115559D03*
X263086Y147675D03*
X265722Y463102D03*
X265737Y473680D03*
X264516Y497341D03*
X255837Y823626D03*
X255687Y812192D03*
X264181Y847354D03*
X262559Y1191777D03*
X271943Y147630D03*
X271547Y260353D03*
X281193Y256624D03*
X281074Y322688D03*
X289895D03*
X281569Y436169D03*
X291002Y432844D03*
X273405Y497341D03*
X285348Y610540D03*
X270109Y672192D03*
X278955D03*
X273114Y785968D03*
X282737Y782643D03*
X273305Y847237D03*
X285966Y959767D03*
X281124Y1016162D03*
X290107D03*
X282958Y1134471D03*
X272082Y1191777D03*
X283808Y1308959D03*
X279518Y1374543D03*
X270579Y1374626D03*
X279990Y1479435D03*
X270234Y1482760D03*
X291054Y1543211D03*
X284086Y1659883D03*
X284583Y1723465D03*
X274704Y1723196D03*
X281066Y1834569D03*
X291550Y1829846D03*
X280240Y1858668D03*
X279976Y1864565D03*
X282717Y1898327D03*
X273817D03*
X304151Y78778D03*
X313089D03*
X294483Y82732D03*
X308057Y248863D03*
X306267Y241010D03*
X314914Y238162D03*
X314940Y252083D03*
X295509Y607215D03*
X295874Y956442D03*
X309678Y1053262D03*
X292698Y1131146D03*
X312527Y1162266D03*
X312698Y1172804D03*
X294133Y1305634D03*
X314183Y1403423D03*
X302267Y1524401D03*
X301734Y1513883D03*
X300392Y1543211D03*
X312077Y1575871D03*
X294090Y1656558D03*
X314562Y2009087D03*
X331403Y51409D03*
X333889Y56021D03*
X338227Y61559D03*
X322005Y78778D03*
X320372Y225979D03*
X318088Y231820D03*
X321899Y238137D03*
X331046Y232021D03*
X320961Y250105D03*
X324709Y231580D03*
X335522Y404033D03*
X323313Y418313D03*
X326196Y413982D03*
X328950Y409216D03*
X320980Y423225D03*
X336617Y577978D03*
X319305Y582111D03*
X329636Y584715D03*
X317724Y588250D03*
X337387Y586230D03*
X320380Y576491D03*
X331867Y589810D03*
X333750Y595326D03*
X321742Y599041D03*
X331568Y752967D03*
X339012Y752859D03*
X329336Y762693D03*
X334010Y758588D03*
X327524Y758020D03*
X329938Y948756D03*
X332527Y943746D03*
X324098Y946104D03*
X318557Y941178D03*
X323868Y929978D03*
X326646Y939788D03*
X336160Y937262D03*
X328583Y933262D03*
X321425Y951577D03*
X324246Y1051786D03*
X335677Y1048904D03*
X317592Y1053050D03*
X337509Y1109598D03*
X328989Y1121090D03*
X326558Y1126368D03*
X327452Y1279447D03*
X321978Y1282086D03*
X329619Y1284016D03*
X327932Y1289221D03*
X325636Y1399114D03*
X334646Y1400804D03*
X323720Y1570924D03*
X333474Y1566686D03*
X335963Y1573797D03*
X323813Y1753231D03*
X329887Y1752081D03*
X332399Y1926787D03*
X324803Y2005272D03*
X359931Y52189D03*
X348289Y50863D03*
X345089Y56190D03*
X340373Y51579D03*
X362227Y299380D03*
X356831Y299956D03*
X360533Y339095D03*
X342097Y401684D03*
X363825Y401768D03*
X342900Y580126D03*
X364353Y650514D03*
X358911Y650530D03*
X347227Y694078D03*
X352358Y698363D03*
X362531Y694417D03*
X362577Y752783D03*
X344109Y751809D03*
X343656Y933725D03*
X345578Y1047844D03*
X344099Y1106798D03*
X344130Y1401670D03*
X350690Y1403243D03*
X348710Y1570187D03*
X361011Y1568890D03*
X343402Y1572080D03*
X348245Y1575241D03*
X355364Y1570990D03*
X361039Y1875684D03*
X353250Y1874308D03*
X347105Y1875191D03*
X345537Y1916558D03*
X344402Y1911123D03*
X353726Y1914205D03*
X360118Y1912411D03*
X363361Y1918313D03*
X358318Y1920680D03*
X363411Y1923459D03*
X340336Y1922409D03*
X372204Y56126D03*
X379257Y52158D03*
X387524Y76847D03*
X373942Y300523D03*
X368544Y300470D03*
X367076Y340100D03*
X374442Y406857D03*
X374542Y401282D03*
X368907Y404308D03*
X368680Y694668D03*
X376654Y754748D03*
X382892Y767710D03*
X386790Y774338D03*
X379335Y1189778D03*
X383276Y1184136D03*
X386816Y1179841D03*
X376472Y1194999D03*
X373674Y1199967D03*
X371523Y1204725D03*
X385261Y1334686D03*
X378904Y1333844D03*
X381725Y1340790D03*
X373499Y1340730D03*
X377984Y1383142D03*
X380378Y1377228D03*
X367829Y1566108D03*
X365922Y1870477D03*
X374431Y1901397D03*
X374775Y1919243D03*
X379403Y1917261D03*
X369748Y1921795D03*
G54D40*
G01X104331Y0D02*
X397638D01*
G03X405512Y7874I0J7874D01*
G01Y2078740D01*
G03X397638Y2086614I-7874J0D01*
G01X104331D01*
G03X98425Y2080709I0J-5906D01*
G01Y2076772D01*
G02X92520Y2070866I-5905J-1D01*
G01X5906D01*
G03X0Y2064961I-1J-5905D01*
G01Y21654D01*
G03X5906Y15748I5906J0D01*
G01X92520D01*
G02X98425Y9843I0J-5905D01*
G01Y5906D01*
G03X104331Y0I5906J0D01*
G54D31*
X163385Y27205D03*
Y202205D03*
Y377205D03*
X163386Y552205D03*
Y727205D03*
X163385Y902205D03*
Y1077205D03*
Y1252205D03*
Y1427205D03*
Y1602205D03*
Y1777205D03*
Y1952205D03*
X373385Y32520D03*
Y207520D03*
Y382520D03*
X373386Y557520D03*
Y732520D03*
X373385Y907520D03*
Y1082520D03*
Y1257520D03*
Y1432520D03*
Y1607520D03*
Y1782520D03*
Y1957520D03*
G54D22*
X45056Y1817693D03*
G54D13*
X14073Y512197D03*
Y522000D03*
Y552000D03*
Y561803D03*
Y1580004D03*
Y1570201D03*
Y1610004D03*
Y1619807D03*
X65254Y519500D03*
Y529500D03*
Y539500D03*
X55254Y524500D03*
Y534500D03*
X65254Y549500D03*
X55254Y544500D03*
X65254Y1577504D03*
Y1587504D03*
Y1597504D03*
X55254Y1582504D03*
Y1592504D03*
Y1602504D03*
X65254Y1607504D03*
G54D41*
G01X-723776Y2987387D02*
Y-376795D01*
Y-489221D01*
X1782976D01*
Y-376795D01*
Y2987387D01*
X-723776D01*
G01X-4000Y-62500D02*
Y-137500D01*
X496000D01*
Y-62500D01*
X-4000D01*
G01X104331Y0D02*
X397638D01*
G03X405512Y7874I0J7874D01*
G01Y2078740D01*
G03X397638Y2086614I-7874J0D01*
G01X104331D01*
G03X98425Y2080709I0J-5906D01*
G01Y2076772D01*
G02X92520Y2070866I-5905J-1D01*
G01X5906D01*
G03X0Y2064961I-1J-5905D01*
G01Y21654D01*
G03X5906Y15748I5906J0D01*
G01X92520D01*
G02X98425Y9843I0J-5905D01*
G01Y5906D01*
G03X104331Y0I5906J0D01*
G01X8000Y-127500D02*
Y-132500D01*
G01X6543Y-127500D02*
X9457D01*
G01X14367Y-132500D02*
X11833D01*
Y-127500D01*
X14367D01*
G01X13353Y-129917D02*
X11833D01*
G01X16933Y-127500D02*
Y-132500D01*
X19467D01*
G01X23300Y-132667D02*
X23173Y-132583D01*
Y-132417D01*
X23300Y-132333D01*
X23427Y-132417D01*
Y-132583D01*
X23300Y-132667D01*
G01Y-130417D02*
X23173Y-130333D01*
Y-130167D01*
X23300Y-130083D01*
X23427Y-130167D01*
Y-130333D01*
X23300Y-130417D01*
G01X28083Y-134167D02*
X27450Y-133333D01*
X27133Y-132500D01*
Y-129167D01*
X27450Y-128333D01*
X28083Y-127500D01*
G01X33500D02*
X32993Y-127667D01*
X32613Y-128083D01*
X32360Y-128583D01*
X32170Y-129250D01*
X32107Y-130000D01*
X32170Y-130750D01*
X32360Y-131417D01*
X32613Y-131917D01*
X32993Y-132333D01*
X33500Y-132500D01*
X34007Y-132333D01*
X34387Y-131917D01*
X34640Y-131417D01*
X34830Y-130750D01*
X34893Y-130000D01*
X34830Y-129250D01*
X34640Y-128583D01*
X34387Y-128083D01*
X34007Y-127667D01*
X33500Y-127500D01*
G01X37207Y-131500D02*
X37587Y-132083D01*
X38093Y-132417D01*
X38663Y-132500D01*
X39170Y-132417D01*
X39677Y-132000D01*
X39993Y-131500D01*
X40057Y-131000D01*
X39930Y-130417D01*
X39487Y-130000D01*
X39043Y-129833D01*
X38473D01*
G01X39043D02*
X39423Y-129583D01*
X39740Y-129167D01*
X39867Y-128667D01*
X39740Y-128167D01*
X39423Y-127750D01*
X38853Y-127500D01*
X38283Y-127583D01*
X37713Y-127917D01*
G01X44017Y-134167D02*
X44650Y-133333D01*
X44967Y-132500D01*
Y-129167D01*
X44650Y-128333D01*
X44017Y-127500D01*
G01X47407Y-131500D02*
X47787Y-132083D01*
X48293Y-132417D01*
X48863Y-132500D01*
X49370Y-132417D01*
X49877Y-132000D01*
X50193Y-131500D01*
X50257Y-131000D01*
X50130Y-130417D01*
X49687Y-130000D01*
X49243Y-129833D01*
X48673D01*
G01X49243D02*
X49623Y-129583D01*
X49940Y-129167D01*
X50067Y-128667D01*
X49940Y-128167D01*
X49623Y-127750D01*
X49053Y-127500D01*
X48483Y-127583D01*
X47913Y-127917D01*
G01X52697Y-128333D02*
X53077Y-127833D01*
X53520Y-127583D01*
X54027Y-127500D01*
X54660Y-127667D01*
X55103Y-128083D01*
X55230Y-128583D01*
X55167Y-129083D01*
X54913Y-129500D01*
X53647Y-130333D01*
X53077Y-130917D01*
X52697Y-131750D01*
X52570Y-132500D01*
X55230D01*
G01X58873D02*
X59000Y-131417D01*
X59190Y-130500D01*
X59443Y-129667D01*
X59760Y-128750D01*
X60267Y-127500D01*
X57733D01*
G01X63277Y-130833D02*
X64923D01*
G01X67997Y-128333D02*
X68377Y-127833D01*
X68820Y-127583D01*
X69327Y-127500D01*
X69960Y-127667D01*
X70403Y-128083D01*
X70530Y-128583D01*
X70467Y-129083D01*
X70213Y-129500D01*
X68947Y-130333D01*
X68377Y-130917D01*
X67997Y-131750D01*
X67870Y-132500D01*
X70530D01*
G01X72907Y-131500D02*
X73287Y-132083D01*
X73793Y-132417D01*
X74363Y-132500D01*
X74870Y-132417D01*
X75377Y-132000D01*
X75693Y-131500D01*
X75757Y-131000D01*
X75630Y-130417D01*
X75187Y-130000D01*
X74743Y-129833D01*
X74173D01*
G01X74743D02*
X75123Y-129583D01*
X75440Y-129167D01*
X75567Y-128667D01*
X75440Y-128167D01*
X75123Y-127750D01*
X74553Y-127500D01*
X73983Y-127583D01*
X73413Y-127917D01*
G01X80160Y-132500D02*
Y-127500D01*
X77817Y-131083D01*
X80983D01*
G01X83107Y-131750D02*
X83487Y-132167D01*
X83930Y-132417D01*
X84500Y-132500D01*
X85070Y-132333D01*
X85513Y-132000D01*
X85830Y-131417D01*
X85893Y-130750D01*
X85767Y-130083D01*
X85450Y-129667D01*
X85007Y-129333D01*
X84563Y-129250D01*
X84120Y-129333D01*
X83550Y-129667D01*
X83740Y-127500D01*
X85450D01*
G01X93497Y-132500D02*
Y-127500D01*
X95903D01*
G01X95017Y-129917D02*
X93497D01*
G01X98217Y-132500D02*
X99800Y-127500D01*
X101383Y-132500D01*
G01X100813Y-130750D02*
X98787D01*
G01X103570Y-132500D02*
X106230Y-127500D01*
G01X103570D02*
X106230Y-132500D01*
G01X110000Y-132667D02*
X109873Y-132583D01*
Y-132417D01*
X110000Y-132333D01*
X110127Y-132417D01*
Y-132583D01*
X110000Y-132667D01*
G01Y-130417D02*
X109873Y-130333D01*
Y-130167D01*
X110000Y-130083D01*
X110127Y-130167D01*
Y-130333D01*
X110000Y-130417D01*
G01X114783Y-134167D02*
X114150Y-133333D01*
X113833Y-132500D01*
Y-129167D01*
X114150Y-128333D01*
X114783Y-127500D01*
G01X120200D02*
X119693Y-127667D01*
X119313Y-128083D01*
X119060Y-128583D01*
X118870Y-129250D01*
X118807Y-130000D01*
X118870Y-130750D01*
X119060Y-131417D01*
X119313Y-131917D01*
X119693Y-132333D01*
X120200Y-132500D01*
X120707Y-132333D01*
X121087Y-131917D01*
X121340Y-131417D01*
X121530Y-130750D01*
X121593Y-130000D01*
X121530Y-129250D01*
X121340Y-128583D01*
X121087Y-128083D01*
X120707Y-127667D01*
X120200Y-127500D01*
G01X123907Y-131500D02*
X124287Y-132083D01*
X124793Y-132417D01*
X125363Y-132500D01*
X125870Y-132417D01*
X126377Y-132000D01*
X126693Y-131500D01*
X126757Y-131000D01*
X126630Y-130417D01*
X126187Y-130000D01*
X125743Y-129833D01*
X125173D01*
G01X125743D02*
X126123Y-129583D01*
X126440Y-129167D01*
X126567Y-128667D01*
X126440Y-128167D01*
X126123Y-127750D01*
X125553Y-127500D01*
X124983Y-127583D01*
X124413Y-127917D01*
G01X130717Y-134167D02*
X131350Y-133333D01*
X131667Y-132500D01*
Y-129167D01*
X131350Y-128333D01*
X130717Y-127500D01*
G01X134107Y-131500D02*
X134487Y-132083D01*
X134993Y-132417D01*
X135563Y-132500D01*
X136070Y-132417D01*
X136577Y-132000D01*
X136893Y-131500D01*
X136957Y-131000D01*
X136830Y-130417D01*
X136387Y-130000D01*
X135943Y-129833D01*
X135373D01*
G01X135943D02*
X136323Y-129583D01*
X136640Y-129167D01*
X136767Y-128667D01*
X136640Y-128167D01*
X136323Y-127750D01*
X135753Y-127500D01*
X135183Y-127583D01*
X134613Y-127917D01*
G01X139523Y-131917D02*
X139967Y-132333D01*
X140473Y-132500D01*
X140980Y-132333D01*
X141423Y-131833D01*
X141740Y-131083D01*
X141867Y-130333D01*
Y-129417D01*
X141740Y-128667D01*
X141423Y-128000D01*
X141043Y-127667D01*
X140600Y-127500D01*
X140093Y-127667D01*
X139713Y-128000D01*
X139460Y-128500D01*
X139333Y-129167D01*
X139460Y-129750D01*
X139777Y-130333D01*
X140157Y-130667D01*
X140600Y-130750D01*
X141107Y-130583D01*
X141487Y-130167D01*
X141867Y-129417D01*
G01X145573Y-132500D02*
X145700Y-131417D01*
X145890Y-130500D01*
X146143Y-129667D01*
X146460Y-128750D01*
X146967Y-127500D01*
X144433D01*
G01X149977Y-130833D02*
X151623D01*
G01X154507Y-131500D02*
X154887Y-132083D01*
X155393Y-132417D01*
X155963Y-132500D01*
X156470Y-132417D01*
X156977Y-132000D01*
X157293Y-131500D01*
X157357Y-131000D01*
X157230Y-130417D01*
X156787Y-130000D01*
X156343Y-129833D01*
X155773D01*
G01X156343D02*
X156723Y-129583D01*
X157040Y-129167D01*
X157167Y-128667D01*
X157040Y-128167D01*
X156723Y-127750D01*
X156153Y-127500D01*
X155583Y-127583D01*
X155013Y-127917D01*
G01X159797Y-130417D02*
X160240Y-129833D01*
X160620Y-129500D01*
X161127Y-129333D01*
X161570Y-129500D01*
X161887Y-129833D01*
X162140Y-130333D01*
X162203Y-130917D01*
X162140Y-131417D01*
X161887Y-131917D01*
X161507Y-132333D01*
X161063Y-132500D01*
X160557Y-132333D01*
X160113Y-131833D01*
X159860Y-131083D01*
X159797Y-130250D01*
X159923Y-129167D01*
X160113Y-128583D01*
X160430Y-128000D01*
X160873Y-127583D01*
X161317Y-127500D01*
X161760Y-127667D01*
X162077Y-128083D01*
G01X166100Y-132500D02*
Y-127500D01*
X165340Y-128500D01*
G01Y-132500D02*
X166860D01*
G01X171960D02*
Y-127500D01*
X169617Y-131083D01*
X172783D01*
G01X191000Y-62500D02*
Y-137500D01*
G01Y-112500D02*
X294000D01*
Y-87500D01*
G01X191000D02*
X294000D01*
G01X301507Y-122500D02*
Y-117500D01*
X302773D01*
X303280Y-117750D01*
X303660Y-118083D01*
X303977Y-118583D01*
X304230Y-119167D01*
X304293Y-120000D01*
X304230Y-120833D01*
X303977Y-121417D01*
X303660Y-121917D01*
X303280Y-122250D01*
X302773Y-122500D01*
X301507D01*
G01X306417D02*
X308000Y-117500D01*
X309583Y-122500D01*
G01X309013Y-120750D02*
X306987D01*
G01X313100Y-117500D02*
Y-122500D01*
G01X311643Y-117500D02*
X314557D01*
G01X319467Y-122500D02*
X316933D01*
Y-117500D01*
X319467D01*
G01X318453Y-119917D02*
X316933D01*
G01X323300Y-122667D02*
X323173Y-122583D01*
Y-122417D01*
X323300Y-122333D01*
X323427Y-122417D01*
Y-122583D01*
X323300Y-122667D01*
G01Y-120417D02*
X323173Y-120333D01*
Y-120167D01*
X323300Y-120083D01*
X323427Y-120167D01*
Y-120333D01*
X323300Y-120417D01*
G01X296000Y-62500D02*
Y-137500D01*
G01X294000Y-62500D02*
Y-137500D01*
G01X301633Y-97500D02*
Y-92500D01*
X303153D01*
X303660Y-92750D01*
X304040Y-93333D01*
X304167Y-94000D01*
X304040Y-94667D01*
X303723Y-95167D01*
X303153Y-95417D01*
X301633D01*
G01X306860Y-97667D02*
X309140Y-92500D01*
G01X311643Y-97500D02*
Y-92500D01*
X314557Y-97500D01*
Y-92500D01*
G01X318200Y-97667D02*
X318073Y-97583D01*
Y-97417D01*
X318200Y-97333D01*
X318327Y-97417D01*
Y-97583D01*
X318200Y-97667D01*
G01Y-95417D02*
X318073Y-95333D01*
Y-95167D01*
X318200Y-95083D01*
X318327Y-95167D01*
Y-95333D01*
X318200Y-95417D01*
G01X296000Y-112500D02*
X496000D01*
G01X301633Y-72500D02*
Y-67500D01*
X303153D01*
X303660Y-67750D01*
X304040Y-68333D01*
X304167Y-69000D01*
X304040Y-69667D01*
X303723Y-70167D01*
X303153Y-70417D01*
X301633D01*
G01X306733Y-72500D02*
Y-67500D01*
X308317D01*
X308823Y-67750D01*
X309140Y-68083D01*
X309267Y-68750D01*
X309140Y-69417D01*
X308760Y-69833D01*
X308317Y-70083D01*
X306733D01*
G01X308317D02*
X309267Y-72500D01*
G01X313100D02*
X312593Y-72417D01*
X312150Y-72083D01*
X311770Y-71583D01*
X311517Y-71000D01*
X311390Y-70333D01*
Y-69667D01*
X311517Y-69000D01*
X311770Y-68417D01*
X312150Y-67917D01*
X312593Y-67583D01*
X313100Y-67500D01*
X313607Y-67583D01*
X314050Y-67917D01*
X314430Y-68417D01*
X314683Y-69000D01*
X314810Y-69667D01*
Y-70333D01*
X314683Y-71000D01*
X314430Y-71583D01*
X314050Y-72083D01*
X313607Y-72417D01*
X313100Y-72500D01*
G01X316933Y-71500D02*
X317250Y-72000D01*
X317630Y-72333D01*
X318073Y-72500D01*
X318580Y-72333D01*
X318960Y-72000D01*
X319340Y-71500D01*
X319467Y-70833D01*
Y-67500D01*
G01X324567Y-72500D02*
X322033D01*
Y-67500D01*
X324567D01*
G01X323553Y-69917D02*
X322033D01*
G01X329793Y-67917D02*
X329413Y-67667D01*
X328970Y-67500D01*
X328463D01*
X327893Y-67750D01*
X327450Y-68167D01*
X327133Y-68667D01*
X326880Y-69500D01*
X326817Y-70250D01*
X326943Y-71000D01*
X327133Y-71500D01*
X327513Y-72000D01*
X327957Y-72333D01*
X328400Y-72500D01*
X328843D01*
X329287Y-72333D01*
X329667Y-72083D01*
X329983Y-71750D01*
G01X333500Y-67500D02*
Y-72500D01*
G01X332043Y-67500D02*
X334957D01*
G01X338600Y-72667D02*
X338473Y-72583D01*
Y-72417D01*
X338600Y-72333D01*
X338727Y-72417D01*
Y-72583D01*
X338600Y-72667D01*
G01Y-70417D02*
X338473Y-70333D01*
Y-70167D01*
X338600Y-70083D01*
X338727Y-70167D01*
Y-70333D01*
X338600Y-70417D01*
G01X296000Y-87500D02*
X496000D01*
G01X411000Y-112500D02*
Y-137500D01*
G01X416633Y-122500D02*
Y-117500D01*
X418217D01*
X418723Y-117750D01*
X419040Y-118083D01*
X419167Y-118750D01*
X419040Y-119417D01*
X418660Y-119833D01*
X418217Y-120083D01*
X416633D01*
G01X418217D02*
X419167Y-122500D01*
G01X424267D02*
X421733D01*
Y-117500D01*
X424267D01*
G01X423253Y-119917D02*
X421733D01*
G01X426517Y-117500D02*
X428100Y-122500D01*
X429683Y-117500D01*
G01X433200Y-122667D02*
X433073Y-122583D01*
Y-122417D01*
X433200Y-122333D01*
X433327Y-122417D01*
Y-122583D01*
X433200Y-122667D01*
G01Y-120417D02*
X433073Y-120333D01*
Y-120167D01*
X433200Y-120083D01*
X433327Y-120167D01*
Y-120333D01*
X433200Y-120417D01*
G01X460000Y-112500D02*
Y-137500D01*
G01X-723776Y2987387D02*
Y-376795D01*
Y-489221D01*
X1782976D01*
Y-376795D01*
Y2987387D01*
X-723776D01*
G01X6705Y-124160D02*
X7332Y-124685D01*
X8037Y-125000D01*
X8663D01*
X9290Y-124685D01*
X9760Y-124160D01*
X9995Y-123425D01*
X9838Y-122690D01*
X9447Y-122060D01*
X8742Y-121640D01*
X7802Y-121430D01*
X7253Y-121010D01*
X7018Y-120275D01*
X7175Y-119540D01*
X7567Y-119015D01*
X8115Y-118700D01*
X8663D01*
X9212Y-118910D01*
X9682Y-119435D01*
G01X13005Y-125000D02*
Y-118700D01*
G01X16295D02*
Y-125000D01*
G01Y-121850D02*
X13005D01*
G01X20010Y-118700D02*
X21890D01*
G01X20950D02*
Y-125000D01*
G01X20010D02*
X21890D01*
G01X28817D02*
X25683D01*
Y-118700D01*
X28817D01*
G01X27563Y-121745D02*
X25683D01*
G01X31748Y-125000D02*
Y-118700D01*
X35352Y-125000D01*
Y-118700D01*
G01X39693Y-126155D02*
X40007Y-124790D01*
G01X46150Y-118700D02*
Y-125000D01*
G01X44348Y-118700D02*
X47952D01*
G01X50492Y-125000D02*
X52450Y-118700D01*
X54408Y-125000D01*
G01X53703Y-122795D02*
X51197D01*
G01X57810Y-118700D02*
X59690D01*
G01X58750D02*
Y-125000D01*
G01X57810D02*
X59690D01*
G01X62700Y-118700D02*
X63797Y-125000D01*
X65050Y-118700D01*
X66303Y-125000D01*
X67400Y-118700D01*
G01X69392Y-125000D02*
X71350Y-118700D01*
X73308Y-125000D01*
G01X72603Y-122795D02*
X70097D01*
G01X75848Y-125000D02*
Y-118700D01*
X79452Y-125000D01*
Y-118700D01*
G01X88683Y-125000D02*
Y-118700D01*
X90642D01*
X91268Y-119015D01*
X91660Y-119435D01*
X91817Y-120275D01*
X91660Y-121115D01*
X91190Y-121640D01*
X90642Y-121955D01*
X88683D01*
G01X90642D02*
X91817Y-125000D01*
G01X96550Y-125210D02*
X96393Y-125105D01*
Y-124895D01*
X96550Y-124790D01*
X96707Y-124895D01*
Y-125105D01*
X96550Y-125210D01*
G01X102850Y-125000D02*
X102223Y-124895D01*
X101675Y-124475D01*
X101205Y-123845D01*
X100892Y-123110D01*
X100735Y-122270D01*
Y-121430D01*
X100892Y-120590D01*
X101205Y-119855D01*
X101675Y-119225D01*
X102223Y-118805D01*
X102850Y-118700D01*
X103477Y-118805D01*
X104025Y-119225D01*
X104495Y-119855D01*
X104808Y-120590D01*
X104965Y-121430D01*
Y-122270D01*
X104808Y-123110D01*
X104495Y-123845D01*
X104025Y-124475D01*
X103477Y-124895D01*
X102850Y-125000D01*
G01X109150Y-125210D02*
X108993Y-125105D01*
Y-124895D01*
X109150Y-124790D01*
X109307Y-124895D01*
Y-125105D01*
X109150Y-125210D01*
G01X117173Y-119225D02*
X116703Y-118910D01*
X116155Y-118700D01*
X115528D01*
X114823Y-119015D01*
X114275Y-119540D01*
X113883Y-120170D01*
X113570Y-121220D01*
X113492Y-122165D01*
X113648Y-123110D01*
X113883Y-123740D01*
X114353Y-124370D01*
X114902Y-124790D01*
X115450Y-125000D01*
X115998D01*
X116547Y-124790D01*
X117017Y-124475D01*
X117408Y-124055D01*
G01X121750Y-125210D02*
X121593Y-125105D01*
Y-124895D01*
X121750Y-124790D01*
X121907Y-124895D01*
Y-125105D01*
X121750Y-125210D01*
G01X6627Y-115000D02*
Y-108700D01*
G01X9603D02*
X6627Y-112585D01*
G01X10073Y-115000D02*
X7958Y-110800D01*
G01X12927Y-108700D02*
Y-113215D01*
X13240Y-114160D01*
X13867Y-114790D01*
X14650Y-115000D01*
X15433Y-114790D01*
X16060Y-114160D01*
X16373Y-113215D01*
Y-108700D01*
G01X22517Y-115000D02*
X19383D01*
Y-108700D01*
X22517D01*
G01X21263Y-111745D02*
X19383D01*
G01X26310Y-108700D02*
X28190D01*
G01X27250D02*
Y-115000D01*
G01X26310D02*
X28190D01*
G01X38205Y-114160D02*
X38832Y-114685D01*
X39537Y-115000D01*
X40163D01*
X40790Y-114685D01*
X41260Y-114160D01*
X41495Y-113425D01*
X41338Y-112690D01*
X40947Y-112060D01*
X40242Y-111640D01*
X39302Y-111430D01*
X38753Y-111010D01*
X38518Y-110275D01*
X38675Y-109540D01*
X39067Y-109015D01*
X39615Y-108700D01*
X40163D01*
X40712Y-108910D01*
X41182Y-109435D01*
G01X44505Y-115000D02*
Y-108700D01*
G01X47795D02*
Y-115000D01*
G01Y-111850D02*
X44505D01*
G01X50492Y-115000D02*
X52450Y-108700D01*
X54408Y-115000D01*
G01X53703Y-112795D02*
X51197D01*
G01X56948Y-115000D02*
Y-108700D01*
X60552Y-115000D01*
Y-108700D01*
G01X69705Y-115000D02*
Y-108700D01*
G01X72995D02*
Y-115000D01*
G01Y-111850D02*
X69705D01*
G01X76005Y-114160D02*
X76632Y-114685D01*
X77337Y-115000D01*
X77963D01*
X78590Y-114685D01*
X79060Y-114160D01*
X79295Y-113425D01*
X79138Y-112690D01*
X78747Y-112060D01*
X78042Y-111640D01*
X77102Y-111430D01*
X76553Y-111010D01*
X76318Y-110275D01*
X76475Y-109540D01*
X76867Y-109015D01*
X77415Y-108700D01*
X77963D01*
X78512Y-108910D01*
X78982Y-109435D01*
G01X83010Y-108700D02*
X84890D01*
G01X83950D02*
Y-115000D01*
G01X83010D02*
X84890D01*
G01X88292D02*
X90250Y-108700D01*
X92208Y-115000D01*
G01X91503Y-112795D02*
X88997D01*
G01X94748Y-115000D02*
Y-108700D01*
X98352Y-115000D01*
Y-108700D01*
G01X103320Y-111850D02*
X104887D01*
Y-113740D01*
X104417Y-114370D01*
X103868Y-114790D01*
X103085Y-115000D01*
X102302Y-114790D01*
X101753Y-114370D01*
X101283Y-113740D01*
X100970Y-113005D01*
X100813Y-112165D01*
Y-111430D01*
X100970Y-110800D01*
X101283Y-110065D01*
X101753Y-109435D01*
X102223Y-109015D01*
X102850Y-108700D01*
X103398D01*
X104025Y-108910D01*
X104495Y-109330D01*
G01X108993Y-116155D02*
X109307Y-114790D01*
G01X115450Y-108700D02*
Y-115000D01*
G01X113648Y-108700D02*
X117252D01*
G01X119792Y-115000D02*
X121750Y-108700D01*
X123708Y-115000D01*
G01X123003Y-112795D02*
X120497D01*
G01X128050Y-115000D02*
X127423Y-114895D01*
X126875Y-114475D01*
X126405Y-113845D01*
X126092Y-113110D01*
X125935Y-112270D01*
Y-111430D01*
X126092Y-110590D01*
X126405Y-109855D01*
X126875Y-109225D01*
X127423Y-108805D01*
X128050Y-108700D01*
X128677Y-108805D01*
X129225Y-109225D01*
X129695Y-109855D01*
X130008Y-110590D01*
X130165Y-111430D01*
Y-112270D01*
X130008Y-113110D01*
X129695Y-113845D01*
X129225Y-114475D01*
X128677Y-114895D01*
X128050Y-115000D01*
G01X140650D02*
Y-112165D01*
X139083Y-108700D01*
G01X142217D02*
X140650Y-112165D01*
G01X145227Y-108700D02*
Y-113215D01*
X145540Y-114160D01*
X146167Y-114790D01*
X146950Y-115000D01*
X147733Y-114790D01*
X148360Y-114160D01*
X148673Y-113215D01*
Y-108700D01*
G01X151292Y-115000D02*
X153250Y-108700D01*
X155208Y-115000D01*
G01X154503Y-112795D02*
X151997D01*
G01X157748Y-115000D02*
Y-108700D01*
X161352Y-115000D01*
Y-108700D01*
G01X30650Y-92300D02*
X28130Y-91883D01*
X25925Y-90217D01*
X24035Y-87717D01*
X22775Y-84800D01*
X22145Y-81467D01*
Y-78133D01*
X22775Y-74800D01*
X24035Y-71883D01*
X25925Y-69384D01*
X28130Y-67717D01*
X30650Y-67300D01*
X33170Y-67717D01*
X35375Y-69384D01*
X37265Y-71883D01*
X38525Y-74800D01*
X39155Y-78133D01*
Y-81467D01*
X38525Y-84800D01*
X37265Y-87717D01*
X35375Y-90217D01*
X33170Y-91883D01*
X30650Y-92300D01*
G01X33170Y-85633D02*
X36950Y-92300D01*
G01X50495Y-75634D02*
Y-87300D01*
X51755Y-90217D01*
X53645Y-91883D01*
X55850Y-92300D01*
X58055Y-91883D01*
X59945Y-90217D01*
X61205Y-87300D01*
G01Y-92300D02*
Y-75634D01*
G01X86720Y-92300D02*
Y-75634D01*
G01Y-78550D02*
X85460Y-76884D01*
X83570Y-76050D01*
X81365Y-75634D01*
X79160Y-76467D01*
X77270Y-78133D01*
X76010Y-80634D01*
X75380Y-83967D01*
X76010Y-87300D01*
X77270Y-89801D01*
X79160Y-91467D01*
X81365Y-92300D01*
X83570Y-91883D01*
X85460Y-90634D01*
X86720Y-88967D01*
G01X100895Y-92300D02*
Y-75634D01*
G01Y-79800D02*
X102155Y-77717D01*
X104045Y-76050D01*
X106565Y-75634D01*
X108770Y-76050D01*
X110660Y-77717D01*
X111605Y-80634D01*
Y-92300D01*
G01X131450Y-67300D02*
Y-92300D01*
G01X127040Y-75634D02*
X135860D01*
G01X162320Y-92300D02*
Y-75634D01*
G01Y-78550D02*
X161060Y-76884D01*
X159170Y-76050D01*
X156965Y-75634D01*
X154760Y-76467D01*
X152870Y-78133D01*
X151610Y-80634D01*
X150980Y-83967D01*
X151610Y-87300D01*
X152870Y-89801D01*
X154760Y-91467D01*
X156965Y-92300D01*
X159170Y-91883D01*
X161060Y-90634D01*
X162320Y-88967D01*
G01X6548Y-105000D02*
Y-98700D01*
X10152Y-105000D01*
Y-98700D01*
G01X14650Y-105000D02*
X14023Y-104895D01*
X13475Y-104475D01*
X13005Y-103845D01*
X12692Y-103110D01*
X12535Y-102270D01*
Y-101430D01*
X12692Y-100590D01*
X13005Y-99855D01*
X13475Y-99225D01*
X14023Y-98805D01*
X14650Y-98700D01*
X15277Y-98805D01*
X15825Y-99225D01*
X16295Y-99855D01*
X16608Y-100590D01*
X16765Y-101430D01*
Y-102270D01*
X16608Y-103110D01*
X16295Y-103845D01*
X15825Y-104475D01*
X15277Y-104895D01*
X14650Y-105000D01*
G01X20950Y-105210D02*
X20793Y-105105D01*
Y-104895D01*
X20950Y-104790D01*
X21107Y-104895D01*
Y-105105D01*
X20950Y-105210D01*
G01X27250Y-105000D02*
Y-98700D01*
X26310Y-99960D01*
G01Y-105000D02*
X28190D01*
G01X33550D02*
X34098Y-104895D01*
X34725Y-104580D01*
X35117Y-104055D01*
X35273Y-103320D01*
X35117Y-102585D01*
X34647Y-101955D01*
X33942Y-101640D01*
X33158D01*
X32688Y-101430D01*
X32297Y-100905D01*
X32140Y-100170D01*
X32375Y-99435D01*
X32923Y-98910D01*
X33550Y-98700D01*
X34177Y-98910D01*
X34725Y-99435D01*
X34960Y-100170D01*
X34803Y-100905D01*
X34412Y-101430D01*
X33942Y-101640D01*
X33158D01*
X32453Y-101955D01*
X31983Y-102585D01*
X31827Y-103320D01*
X31983Y-104055D01*
X32375Y-104580D01*
X33002Y-104895D01*
X33550Y-105000D01*
G01X39850D02*
X40398Y-104895D01*
X41025Y-104580D01*
X41417Y-104055D01*
X41573Y-103320D01*
X41417Y-102585D01*
X40947Y-101955D01*
X40242Y-101640D01*
X39458D01*
X38988Y-101430D01*
X38597Y-100905D01*
X38440Y-100170D01*
X38675Y-99435D01*
X39223Y-98910D01*
X39850Y-98700D01*
X40477Y-98910D01*
X41025Y-99435D01*
X41260Y-100170D01*
X41103Y-100905D01*
X40712Y-101430D01*
X40242Y-101640D01*
X39458D01*
X38753Y-101955D01*
X38283Y-102585D01*
X38127Y-103320D01*
X38283Y-104055D01*
X38675Y-104580D01*
X39302Y-104895D01*
X39850Y-105000D01*
G01X45993Y-106155D02*
X46307Y-104790D01*
G01X50100Y-98700D02*
X51197Y-105000D01*
X52450Y-98700D01*
X53703Y-105000D01*
X54800Y-98700D01*
G01X60317Y-105000D02*
X57183D01*
Y-98700D01*
X60317D01*
G01X59063Y-101745D02*
X57183D01*
G01X63248Y-105000D02*
Y-98700D01*
X66852Y-105000D01*
Y-98700D01*
G01X76005Y-105000D02*
Y-98700D01*
G01X79295D02*
Y-105000D01*
G01Y-101850D02*
X76005D01*
G01X81600Y-98700D02*
X82697Y-105000D01*
X83950Y-98700D01*
X85203Y-105000D01*
X86300Y-98700D01*
G01X88292Y-105000D02*
X90250Y-98700D01*
X92208Y-105000D01*
G01X91503Y-102795D02*
X88997D01*
G01X101362Y-99750D02*
X101832Y-99120D01*
X102380Y-98805D01*
X103007Y-98700D01*
X103790Y-98910D01*
X104338Y-99435D01*
X104495Y-100065D01*
X104417Y-100695D01*
X104103Y-101220D01*
X102537Y-102270D01*
X101832Y-103005D01*
X101362Y-104055D01*
X101205Y-105000D01*
X104495D01*
G01X107348D02*
Y-98700D01*
X110952Y-105000D01*
Y-98700D01*
G01X113727Y-105000D02*
Y-98700D01*
X115293D01*
X115920Y-99015D01*
X116390Y-99435D01*
X116782Y-100065D01*
X117095Y-100800D01*
X117173Y-101850D01*
X117095Y-102900D01*
X116782Y-103635D01*
X116390Y-104265D01*
X115920Y-104685D01*
X115293Y-105000D01*
X113727D01*
G01X126483D02*
Y-98700D01*
X128442D01*
X129068Y-99015D01*
X129460Y-99435D01*
X129617Y-100275D01*
X129460Y-101115D01*
X128990Y-101640D01*
X128442Y-101955D01*
X126483D01*
G01X128442D02*
X129617Y-105000D01*
G01X132627D02*
Y-98700D01*
X134193D01*
X134820Y-99015D01*
X135290Y-99435D01*
X135682Y-100065D01*
X135995Y-100800D01*
X136073Y-101850D01*
X135995Y-102900D01*
X135682Y-103635D01*
X135290Y-104265D01*
X134820Y-104685D01*
X134193Y-105000D01*
X132627D01*
G01X140650Y-105210D02*
X140493Y-105105D01*
Y-104895D01*
X140650Y-104790D01*
X140807Y-104895D01*
Y-105105D01*
X140650Y-105210D01*
G01X215400Y-105000D02*
Y-97000D01*
X218000Y-103667D01*
X220600Y-97000D01*
Y-105000D01*
G01X223500D02*
X226000Y-97000D01*
X228500Y-105000D01*
G01X227600Y-102200D02*
X224400D01*
G01X231900Y-103934D02*
X232700Y-104600D01*
X233600Y-105000D01*
X234400D01*
X235200Y-104600D01*
X235800Y-103934D01*
X236100Y-103000D01*
X235900Y-102067D01*
X235400Y-101267D01*
X234500Y-100733D01*
X233300Y-100467D01*
X232600Y-99933D01*
X232300Y-99000D01*
X232500Y-98067D01*
X233000Y-97400D01*
X233700Y-97000D01*
X234400D01*
X235100Y-97267D01*
X235700Y-97933D01*
G01X239800Y-105000D02*
Y-97000D01*
G01X243600D02*
X239800Y-101934D01*
G01X244200Y-105000D02*
X241500Y-99667D01*
G01X248700Y-102333D02*
X251300D01*
G01X258800Y-100733D02*
X259200Y-100333D01*
X259500Y-99667D01*
X259700Y-98733D01*
X259500Y-97933D01*
X259100Y-97400D01*
X258400Y-97000D01*
X255700D01*
Y-105000D01*
X259000D01*
X259700Y-104467D01*
X260100Y-103667D01*
X260300Y-102733D01*
X260100Y-101800D01*
X259500Y-101000D01*
X258800Y-100733D01*
X255700D01*
G01X266000Y-105000D02*
X265200Y-104867D01*
X264500Y-104333D01*
X263900Y-103533D01*
X263500Y-102600D01*
X263300Y-101533D01*
Y-100467D01*
X263500Y-99400D01*
X263900Y-98467D01*
X264500Y-97667D01*
X265200Y-97133D01*
X266000Y-97000D01*
X266800Y-97133D01*
X267500Y-97667D01*
X268100Y-98467D01*
X268500Y-99400D01*
X268700Y-100467D01*
Y-101533D01*
X268500Y-102600D01*
X268100Y-103533D01*
X267500Y-104333D01*
X266800Y-104867D01*
X266000Y-105000D01*
G01X274000Y-97000D02*
Y-105000D01*
G01X271700Y-97000D02*
X276300D01*
G01X202000Y-72000D02*
Y-80000D01*
X206000D01*
G01X213800D02*
Y-74667D01*
G01Y-75600D02*
X213400Y-75067D01*
X212800Y-74800D01*
X212100Y-74667D01*
X211400Y-74933D01*
X210800Y-75467D01*
X210400Y-76267D01*
X210200Y-77333D01*
X210400Y-78400D01*
X210800Y-79200D01*
X211400Y-79733D01*
X212100Y-80000D01*
X212800Y-79867D01*
X213400Y-79467D01*
X213800Y-78934D01*
G01X217900Y-82400D02*
X218500Y-82667D01*
X219300Y-82400D01*
X219800Y-81867D01*
X220200Y-81200D01*
X220800Y-79067D01*
X222100Y-74667D01*
G01X218900D02*
X220800Y-79067D01*
G01X226500Y-76400D02*
X229700D01*
X229400Y-75467D01*
X228900Y-74933D01*
X228200Y-74667D01*
X227500Y-74800D01*
X226900Y-75200D01*
X226500Y-76133D01*
X226300Y-76934D01*
Y-77733D01*
X226500Y-78533D01*
X227000Y-79333D01*
X227600Y-79867D01*
X228300Y-80000D01*
X229000Y-79733D01*
X229700Y-78934D01*
G01X234600Y-80000D02*
Y-74667D01*
G01Y-75733D02*
X235100Y-75200D01*
X235600Y-74800D01*
X236300Y-74667D01*
X236800Y-74800D01*
X237400Y-75200D01*
G01X225500Y-122000D02*
Y-130000D01*
G01X223200Y-122000D02*
X227800D01*
G01X233500Y-124667D02*
Y-130000D01*
G01Y-122533D02*
X233300Y-122400D01*
Y-122133D01*
X233500Y-122000D01*
X233700Y-122133D01*
Y-122400D01*
X233500Y-122533D01*
G01X239800Y-130000D02*
Y-124667D01*
G01Y-126000D02*
X240200Y-125333D01*
X240800Y-124800D01*
X241600Y-124667D01*
X242300Y-124800D01*
X242900Y-125333D01*
X243200Y-126267D01*
Y-130000D01*
G01X251300D02*
Y-124667D01*
G01Y-125600D02*
X250900Y-125067D01*
X250300Y-124800D01*
X249600Y-124667D01*
X248900Y-124933D01*
X248300Y-125467D01*
X247900Y-126267D01*
X247700Y-127333D01*
X247900Y-128400D01*
X248300Y-129200D01*
X248900Y-129733D01*
X249600Y-130000D01*
X250300Y-129867D01*
X250900Y-129467D01*
X251300Y-128934D01*
G01X328600Y-123333D02*
X329200Y-122533D01*
X329900Y-122133D01*
X330700Y-122000D01*
X331700Y-122267D01*
X332400Y-122933D01*
X332600Y-123733D01*
X332500Y-124534D01*
X332100Y-125200D01*
X330100Y-126533D01*
X329200Y-127467D01*
X328600Y-128800D01*
X328400Y-130000D01*
X332600D01*
G01X338500Y-122000D02*
X337700Y-122267D01*
X337100Y-122933D01*
X336700Y-123733D01*
X336400Y-124800D01*
X336300Y-126000D01*
X336400Y-127200D01*
X336700Y-128267D01*
X337100Y-129067D01*
X337700Y-129733D01*
X338500Y-130000D01*
X339300Y-129733D01*
X339900Y-129067D01*
X340300Y-128267D01*
X340600Y-127200D01*
X340700Y-126000D01*
X340600Y-124800D01*
X340300Y-123733D01*
X339900Y-122933D01*
X339300Y-122267D01*
X338500Y-122000D01*
G01X346500Y-130000D02*
Y-122000D01*
X345300Y-123600D01*
G01Y-130000D02*
X347700D01*
G01X352300Y-128400D02*
X352900Y-129333D01*
X353700Y-129867D01*
X354600Y-130000D01*
X355400Y-129867D01*
X356200Y-129200D01*
X356700Y-128400D01*
X356800Y-127600D01*
X356600Y-126667D01*
X355900Y-126000D01*
X355200Y-125733D01*
X354300D01*
G01X355200D02*
X355800Y-125333D01*
X356300Y-124667D01*
X356500Y-123867D01*
X356300Y-123067D01*
X355800Y-122400D01*
X354900Y-122000D01*
X354000Y-122133D01*
X353100Y-122667D01*
G01X360700Y-130267D02*
X364300Y-122000D01*
G01X370500D02*
X369700Y-122267D01*
X369100Y-122933D01*
X368700Y-123733D01*
X368400Y-124800D01*
X368300Y-126000D01*
X368400Y-127200D01*
X368700Y-128267D01*
X369100Y-129067D01*
X369700Y-129733D01*
X370500Y-130000D01*
X371300Y-129733D01*
X371900Y-129067D01*
X372300Y-128267D01*
X372600Y-127200D01*
X372700Y-126000D01*
X372600Y-124800D01*
X372300Y-123733D01*
X371900Y-122933D01*
X371300Y-122267D01*
X370500Y-122000D01*
G01X378500Y-130000D02*
Y-122000D01*
X377300Y-123600D01*
G01Y-130000D02*
X379700D01*
G01X384700Y-130267D02*
X388300Y-122000D01*
G01X394500D02*
X393700Y-122267D01*
X393100Y-122933D01*
X392700Y-123733D01*
X392400Y-124800D01*
X392300Y-126000D01*
X392400Y-127200D01*
X392700Y-128267D01*
X393100Y-129067D01*
X393700Y-129733D01*
X394500Y-130000D01*
X395300Y-129733D01*
X395900Y-129067D01*
X396300Y-128267D01*
X396600Y-127200D01*
X396700Y-126000D01*
X396600Y-124800D01*
X396300Y-123733D01*
X395900Y-122933D01*
X395300Y-122267D01*
X394500Y-122000D01*
G01X400800Y-129067D02*
X401500Y-129733D01*
X402300Y-130000D01*
X403100Y-129733D01*
X403800Y-128934D01*
X404300Y-127733D01*
X404500Y-126533D01*
Y-125067D01*
X404300Y-123867D01*
X403800Y-122800D01*
X403200Y-122267D01*
X402500Y-122000D01*
X401700Y-122267D01*
X401100Y-122800D01*
X400700Y-123600D01*
X400500Y-124667D01*
X400700Y-125600D01*
X401200Y-126533D01*
X401800Y-127067D01*
X402500Y-127200D01*
X403300Y-126934D01*
X403900Y-126267D01*
X404500Y-125067D01*
G01X328300Y-105000D02*
Y-97000D01*
X330300D01*
X331100Y-97400D01*
X331700Y-97933D01*
X332200Y-98733D01*
X332600Y-99667D01*
X332700Y-101000D01*
X332600Y-102333D01*
X332200Y-103267D01*
X331700Y-104067D01*
X331100Y-104600D01*
X330300Y-105000D01*
X328300D01*
G01X336000D02*
X338500Y-97000D01*
X341000Y-105000D01*
G01X340100Y-102200D02*
X336900D01*
G01X346500Y-97000D02*
Y-105000D01*
G01X344200Y-97000D02*
X348800D01*
G01X352600Y-101667D02*
X353300Y-100733D01*
X353900Y-100200D01*
X354700Y-99933D01*
X355400Y-100200D01*
X355900Y-100733D01*
X356300Y-101533D01*
X356400Y-102467D01*
X356300Y-103267D01*
X355900Y-104067D01*
X355300Y-104733D01*
X354600Y-105000D01*
X353800Y-104733D01*
X353100Y-103934D01*
X352700Y-102733D01*
X352600Y-101400D01*
X352800Y-99667D01*
X353100Y-98733D01*
X353600Y-97800D01*
X354300Y-97133D01*
X355000Y-97000D01*
X355700Y-97267D01*
X356200Y-97933D01*
G01X359900Y-105000D02*
Y-97000D01*
X362500Y-103667D01*
X365100Y-97000D01*
Y-105000D01*
G01X370500Y-97000D02*
Y-105000D01*
G01X368200Y-97000D02*
X372800D01*
G01X379300Y-100733D02*
X379700Y-100333D01*
X380000Y-99667D01*
X380200Y-98733D01*
X380000Y-97933D01*
X379600Y-97400D01*
X378900Y-97000D01*
X376200D01*
Y-105000D01*
X379500D01*
X380200Y-104467D01*
X380600Y-103667D01*
X380800Y-102733D01*
X380600Y-101800D01*
X380000Y-101000D01*
X379300Y-100733D01*
X376200D01*
G01X386500Y-105000D02*
X387200Y-104867D01*
X388000Y-104467D01*
X388500Y-103800D01*
X388700Y-102867D01*
X388500Y-101934D01*
X387900Y-101133D01*
X387000Y-100733D01*
X386000D01*
X385400Y-100467D01*
X384900Y-99800D01*
X384700Y-98867D01*
X385000Y-97933D01*
X385700Y-97267D01*
X386500Y-97000D01*
X387300Y-97267D01*
X388000Y-97933D01*
X388300Y-98867D01*
X388100Y-99800D01*
X387600Y-100467D01*
X387000Y-100733D01*
X386000D01*
X385100Y-101133D01*
X384500Y-101934D01*
X384300Y-102867D01*
X384500Y-103800D01*
X385000Y-104467D01*
X385800Y-104867D01*
X386500Y-105000D01*
G01X394500D02*
X395200Y-104867D01*
X396000Y-104467D01*
X396500Y-103800D01*
X396700Y-102867D01*
X396500Y-101934D01*
X395900Y-101133D01*
X395000Y-100733D01*
X394000D01*
X393400Y-100467D01*
X392900Y-99800D01*
X392700Y-98867D01*
X393000Y-97933D01*
X393700Y-97267D01*
X394500Y-97000D01*
X395300Y-97267D01*
X396000Y-97933D01*
X396300Y-98867D01*
X396100Y-99800D01*
X395600Y-100467D01*
X395000Y-100733D01*
X394000D01*
X393100Y-101133D01*
X392500Y-101934D01*
X392300Y-102867D01*
X392500Y-103800D01*
X393000Y-104467D01*
X393800Y-104867D01*
X394500Y-105000D01*
G01X400000D02*
X402500Y-97000D01*
X405000Y-105000D01*
G01X404100Y-102200D02*
X400900D01*
G01X410500Y-97000D02*
X409700Y-97267D01*
X409100Y-97933D01*
X408700Y-98733D01*
X408400Y-99800D01*
X408300Y-101000D01*
X408400Y-102200D01*
X408700Y-103267D01*
X409100Y-104067D01*
X409700Y-104733D01*
X410500Y-105000D01*
X411300Y-104733D01*
X411900Y-104067D01*
X412300Y-103267D01*
X412600Y-102200D01*
X412700Y-101000D01*
X412600Y-99800D01*
X412300Y-98733D01*
X411900Y-97933D01*
X411300Y-97267D01*
X410500Y-97000D01*
G01X350500Y-72000D02*
Y-80000D01*
G01X348200Y-72000D02*
X352800D01*
G01X356600Y-76667D02*
X357300Y-75733D01*
X357900Y-75200D01*
X358700Y-74933D01*
X359400Y-75200D01*
X359900Y-75733D01*
X360300Y-76533D01*
X360400Y-77467D01*
X360300Y-78267D01*
X359900Y-79067D01*
X359300Y-79733D01*
X358600Y-80000D01*
X357800Y-79733D01*
X357100Y-78934D01*
X356700Y-77733D01*
X356600Y-76400D01*
X356800Y-74667D01*
X357100Y-73733D01*
X357600Y-72800D01*
X358300Y-72133D01*
X359000Y-72000D01*
X359700Y-72267D01*
X360200Y-72933D01*
G01X363900Y-80000D02*
Y-72000D01*
X366500Y-78667D01*
X369100Y-72000D01*
Y-80000D01*
G01X375100Y-76000D02*
X377100D01*
Y-78400D01*
X376500Y-79200D01*
X375800Y-79733D01*
X374800Y-80000D01*
X373800Y-79733D01*
X373100Y-79200D01*
X372500Y-78400D01*
X372100Y-77467D01*
X371900Y-76400D01*
Y-75467D01*
X372100Y-74667D01*
X372500Y-73733D01*
X373100Y-72933D01*
X373700Y-72400D01*
X374500Y-72000D01*
X375200D01*
X376000Y-72267D01*
X376600Y-72800D01*
G01X379500Y-82667D02*
X385500D01*
G01X388500Y-80000D02*
Y-72000D01*
X390900D01*
X391700Y-72400D01*
X392300Y-73333D01*
X392500Y-74400D01*
X392300Y-75467D01*
X391800Y-76267D01*
X390900Y-76667D01*
X388500D01*
G01X396300Y-80000D02*
Y-72000D01*
X398300D01*
X399100Y-72400D01*
X399700Y-72933D01*
X400200Y-73733D01*
X400600Y-74667D01*
X400700Y-76000D01*
X400600Y-77333D01*
X400200Y-78267D01*
X399700Y-79067D01*
X399100Y-79600D01*
X398300Y-80000D01*
X396300D01*
G01X407300Y-75733D02*
X407700Y-75333D01*
X408000Y-74667D01*
X408200Y-73733D01*
X408000Y-72933D01*
X407600Y-72400D01*
X406900Y-72000D01*
X404200D01*
Y-80000D01*
X407500D01*
X408200Y-79467D01*
X408600Y-78667D01*
X408800Y-77733D01*
X408600Y-76800D01*
X408000Y-76000D01*
X407300Y-75733D01*
X404200D01*
G01X411500Y-82667D02*
X417500D01*
G01X420000Y-80000D02*
X422500Y-72000D01*
X425000Y-80000D01*
G01X424100Y-77200D02*
X420900D01*
G01X427500Y-82667D02*
X433500D01*
G01X439300Y-75733D02*
X439700Y-75333D01*
X440000Y-74667D01*
X440200Y-73733D01*
X440000Y-72933D01*
X439600Y-72400D01*
X438900Y-72000D01*
X436200D01*
Y-80000D01*
X439500D01*
X440200Y-79467D01*
X440600Y-78667D01*
X440800Y-77733D01*
X440600Y-76800D01*
X440000Y-76000D01*
X439300Y-75733D01*
X436200D01*
G01X444300Y-80000D02*
Y-72000D01*
X446300D01*
X447100Y-72400D01*
X447700Y-72933D01*
X448200Y-73733D01*
X448600Y-74667D01*
X448700Y-76000D01*
X448600Y-77333D01*
X448200Y-78267D01*
X447700Y-79067D01*
X447100Y-79600D01*
X446300Y-80000D01*
X444300D01*
G01X443000Y-130000D02*
X445500Y-122000D01*
X448000Y-130000D01*
G01X447100Y-127200D02*
X443900D01*
G01X473000Y-130000D02*
Y-122000D01*
X471800Y-123600D01*
G01Y-130000D02*
X474200D01*
G01X479100Y-126667D02*
X479800Y-125733D01*
X480400Y-125200D01*
X481200Y-124933D01*
X481900Y-125200D01*
X482400Y-125733D01*
X482800Y-126533D01*
X482900Y-127467D01*
X482800Y-128267D01*
X482400Y-129067D01*
X481800Y-129733D01*
X481100Y-130000D01*
X480300Y-129733D01*
X479600Y-128934D01*
X479200Y-127733D01*
X479100Y-126400D01*
X479300Y-124667D01*
X479600Y-123733D01*
X480100Y-122800D01*
X480800Y-122133D01*
X481500Y-122000D01*
X482200Y-122267D01*
X482700Y-122933D01*
G54D14*
X30254Y514500D03*
Y559500D03*
Y1572504D03*
Y1617504D03*
G54D23*
X64979Y35500D03*
Y45500D03*
Y55500D03*
X54979Y40500D03*
Y50500D03*
X64979Y65500D03*
X54979Y60500D03*
X64979Y171500D03*
X54979Y176500D03*
X64979Y181500D03*
Y191500D03*
Y201500D03*
X54979Y186500D03*
Y196500D03*
X64979Y244500D03*
X54979Y249500D03*
X64979Y254500D03*
Y264500D03*
Y274500D03*
X54979Y259500D03*
Y269500D03*
X64979Y380500D03*
Y390500D03*
X54979Y385500D03*
Y395500D03*
X64979Y400500D03*
Y410500D03*
X54979Y405500D03*
X189762Y73105D03*
X190289Y152050D03*
X190357Y247568D03*
X190817Y331786D03*
X189761Y421732D03*
X190553Y506517D03*
X192888Y598130D03*
X190816Y681645D03*
X191846Y774526D03*
X191606Y856244D03*
X196311Y947202D03*
X195516Y1032544D03*
X191250Y1122856D03*
X191342Y1206233D03*
X191846Y1299104D03*
X190552Y1380966D03*
X189463Y1474162D03*
X191079Y1557277D03*
X192143Y1648177D03*
X191607Y1731351D03*
X191530Y1823227D03*
X190289Y1900420D03*
X192125Y1998730D03*
X191530Y2043388D03*
G54D32*
X173385Y32520D03*
Y207520D03*
Y382520D03*
X173386Y557520D03*
Y732520D03*
X173385Y907520D03*
Y1082520D03*
Y1257520D03*
Y1432520D03*
Y1607520D03*
Y1782520D03*
Y1957520D03*
G54D24*
X54979Y70500D03*
Y206500D03*
Y279500D03*
Y415500D03*
X203542Y73105D03*
X204069Y152050D03*
X204137Y247568D03*
X204597Y331786D03*
X203541Y421732D03*
X204333Y506517D03*
X206668Y598130D03*
X204596Y681645D03*
X205626Y774526D03*
X205386Y856244D03*
X210091Y947202D03*
X209296Y1032544D03*
X205030Y1122856D03*
X205122Y1206233D03*
X205626Y1299104D03*
X204332Y1380966D03*
X203243Y1474162D03*
X204859Y1557277D03*
X205923Y1648177D03*
X205387Y1731351D03*
X205310Y1823227D03*
X204069Y1900420D03*
X205905Y1998730D03*
X205310Y2043388D03*
G54D15*
X15547Y707364D03*
X25389D03*
X7673Y703427D03*
X15547Y715238D03*
Y723112D03*
Y730986D03*
X25389Y715238D03*
Y723112D03*
Y730986D03*
X7673Y711301D03*
Y719175D03*
Y727049D03*
X15547Y738860D03*
Y746734D03*
Y754608D03*
X25389Y738860D03*
Y746734D03*
Y754608D03*
X7673Y734923D03*
Y742797D03*
Y750671D03*
Y758545D03*
X15547Y762483D03*
Y770357D03*
Y778231D03*
X25389Y762483D03*
Y770357D03*
Y778231D03*
X7673Y766419D03*
Y774293D03*
Y782167D03*
X15547Y786105D03*
Y793979D03*
Y801853D03*
X25389Y786105D03*
Y793979D03*
Y801853D03*
X7673Y790041D03*
Y797915D03*
Y805790D03*
X15547Y809727D03*
Y817601D03*
Y825475D03*
X25389Y809727D03*
Y817601D03*
Y825475D03*
X7673Y813664D03*
Y821538D03*
Y829412D03*
X15547Y833349D03*
Y841223D03*
Y849097D03*
X25389Y833349D03*
Y841223D03*
Y849097D03*
X7673Y837286D03*
Y845160D03*
Y853034D03*
X15547Y856971D03*
Y864845D03*
Y872719D03*
X25389Y856971D03*
Y864845D03*
Y872719D03*
X7673Y860908D03*
Y868782D03*
Y876656D03*
X15547Y880593D03*
Y888467D03*
Y896341D03*
X25389Y880593D03*
Y888467D03*
Y896341D03*
X7673Y884530D03*
Y892404D03*
Y900278D03*
X15547Y904215D03*
Y912089D03*
Y919963D03*
X25389Y904215D03*
Y912089D03*
Y919963D03*
X7673Y908152D03*
Y916026D03*
Y923900D03*
X15547Y927837D03*
Y935711D03*
Y943585D03*
Y951459D03*
X25389Y927837D03*
Y935711D03*
Y943585D03*
Y951459D03*
X7673Y931774D03*
Y939648D03*
Y947522D03*
X15547Y959333D03*
Y967207D03*
Y975081D03*
X25389Y959333D03*
Y967207D03*
Y975081D03*
X7673Y955396D03*
Y963270D03*
Y971144D03*
Y979018D03*
Y994766D03*
X15547Y990829D03*
Y998703D03*
X25389Y990829D03*
Y998703D03*
X7673Y1002640D03*
Y1010514D03*
Y1018388D03*
X15547Y1006577D03*
Y1014451D03*
Y1022325D03*
X25389Y1006577D03*
Y1014451D03*
Y1022325D03*
X7673Y1026262D03*
X15547Y1030199D03*
X15551Y1065629D03*
X25393D03*
X7677Y1061692D03*
Y1069566D03*
X15551Y1073503D03*
Y1081377D03*
Y1089251D03*
X25393Y1073503D03*
Y1081377D03*
Y1089251D03*
X7677Y1077440D03*
Y1085314D03*
Y1093188D03*
X15551Y1097125D03*
Y1104999D03*
Y1112873D03*
Y1120748D03*
X25393Y1097125D03*
Y1104999D03*
Y1112873D03*
Y1120748D03*
X7677Y1101062D03*
Y1108936D03*
Y1116810D03*
X15551Y1128622D03*
Y1136496D03*
Y1144370D03*
X25393Y1128622D03*
Y1136496D03*
Y1144370D03*
X7677Y1124684D03*
Y1132558D03*
Y1140432D03*
X15551Y1152244D03*
Y1160118D03*
Y1167992D03*
X25393Y1152244D03*
Y1160118D03*
Y1167992D03*
X7677Y1148306D03*
Y1156180D03*
Y1164055D03*
X15551Y1175866D03*
Y1183740D03*
Y1191614D03*
X25393Y1175866D03*
Y1183740D03*
Y1191614D03*
X7677Y1171929D03*
Y1179803D03*
Y1187677D03*
X15551Y1199488D03*
Y1207362D03*
Y1215236D03*
X25393Y1199488D03*
Y1207362D03*
Y1215236D03*
X7677Y1195551D03*
Y1203425D03*
Y1211299D03*
X15551Y1223110D03*
Y1230984D03*
Y1238858D03*
X25393Y1223110D03*
Y1230984D03*
Y1238858D03*
X7677Y1219173D03*
Y1227047D03*
Y1234921D03*
X15551Y1246732D03*
Y1254606D03*
Y1262480D03*
X25393Y1246732D03*
Y1254606D03*
Y1262480D03*
X7677Y1242795D03*
Y1250669D03*
Y1258543D03*
X15551Y1270354D03*
Y1278228D03*
Y1286102D03*
X25393Y1270354D03*
Y1278228D03*
Y1286102D03*
X7677Y1266417D03*
Y1274291D03*
Y1282165D03*
X15551Y1293976D03*
Y1301850D03*
Y1309724D03*
X25393Y1293976D03*
Y1301850D03*
Y1309724D03*
X7677Y1290039D03*
Y1297913D03*
Y1305787D03*
Y1313661D03*
X15551Y1317598D03*
Y1325472D03*
Y1333346D03*
X25393Y1317598D03*
Y1325472D03*
Y1333346D03*
X7677Y1321535D03*
Y1329409D03*
Y1337283D03*
Y1353031D03*
Y1360905D03*
X15551Y1349094D03*
Y1356968D03*
X25393Y1349094D03*
Y1356968D03*
X7677Y1368779D03*
Y1376653D03*
Y1384527D03*
X15551Y1364842D03*
Y1372716D03*
Y1380590D03*
X25393Y1364842D03*
Y1372716D03*
Y1380590D03*
X15551Y1388464D03*
X33263Y703427D03*
Y711301D03*
Y719175D03*
Y727049D03*
Y734923D03*
Y742797D03*
Y750671D03*
Y758545D03*
Y766419D03*
Y774293D03*
Y782167D03*
Y790041D03*
Y797915D03*
Y805790D03*
Y813664D03*
Y821538D03*
Y829412D03*
Y837286D03*
Y845160D03*
Y853034D03*
Y860908D03*
Y868782D03*
Y876656D03*
Y884530D03*
Y892404D03*
Y900278D03*
Y908152D03*
Y916026D03*
Y923900D03*
Y931774D03*
Y939648D03*
Y947522D03*
Y955396D03*
Y963270D03*
Y971144D03*
Y979018D03*
Y994766D03*
Y1002640D03*
Y1010514D03*
Y1018388D03*
Y1026262D03*
X33267Y1061692D03*
Y1069566D03*
Y1077440D03*
Y1085314D03*
Y1093188D03*
Y1101062D03*
Y1108936D03*
Y1116810D03*
Y1124684D03*
Y1132558D03*
Y1140432D03*
Y1148306D03*
Y1156180D03*
Y1164055D03*
Y1171929D03*
Y1179803D03*
Y1187677D03*
Y1195551D03*
Y1203425D03*
Y1211299D03*
Y1219173D03*
Y1227047D03*
Y1234921D03*
Y1242795D03*
Y1250669D03*
Y1258543D03*
Y1266417D03*
Y1274291D03*
Y1282165D03*
Y1290039D03*
Y1297913D03*
Y1305787D03*
Y1313661D03*
Y1321535D03*
Y1329409D03*
Y1337283D03*
Y1353031D03*
Y1360905D03*
Y1368779D03*
Y1376653D03*
Y1384527D03*
G54D33*
X173385Y21890D03*
X183385Y32520D03*
Y21890D03*
X193385Y32520D03*
Y21890D03*
X173385Y196890D03*
X183385D03*
X193385D03*
X183385Y207520D03*
X193385D03*
X173385Y371890D03*
X183385D03*
X193385D03*
X183385Y382520D03*
X193385D03*
X173386Y546890D03*
X183386Y557520D03*
Y546890D03*
X193386Y557520D03*
Y546890D03*
X173386Y721890D03*
X183386Y732520D03*
Y721890D03*
X193386Y732520D03*
Y721890D03*
X173385Y896890D03*
X183385D03*
X193385D03*
X183385Y907520D03*
X193385D03*
X173385Y1071890D03*
X183385D03*
X193385D03*
X183385Y1082520D03*
X193385D03*
X173385Y1246890D03*
X183385Y1257520D03*
Y1246890D03*
X193385Y1257520D03*
Y1246890D03*
X173385Y1421890D03*
X183385Y1432520D03*
Y1421890D03*
X193385Y1432520D03*
Y1421890D03*
X173385Y1596890D03*
X183385D03*
X193385D03*
X183385Y1607520D03*
X193385D03*
X173385Y1771890D03*
X183385D03*
X193385D03*
X183385Y1782520D03*
X193385D03*
X173385Y1946890D03*
X183385Y1957520D03*
Y1946890D03*
X193385Y1957520D03*
Y1946890D03*
X203385Y32520D03*
Y21890D03*
X213385Y32520D03*
Y21890D03*
X203385Y196890D03*
X213385D03*
X203385Y207520D03*
X213385D03*
X203385Y371890D03*
X213385D03*
X203385Y382520D03*
X213385D03*
X203386Y557520D03*
Y546890D03*
X213386Y557520D03*
Y546890D03*
X203386Y732520D03*
Y721890D03*
X213386Y732520D03*
Y721890D03*
X203385Y896890D03*
X213385D03*
X203385Y907520D03*
X213385D03*
X203385Y1071890D03*
X213385D03*
X203385Y1082520D03*
X213385D03*
X203385Y1257520D03*
Y1246890D03*
X213385Y1257520D03*
Y1246890D03*
X203385Y1432520D03*
Y1421890D03*
X213385Y1432520D03*
Y1421890D03*
X203385Y1596890D03*
X213385D03*
X203385Y1607520D03*
X213385D03*
X203385Y1771890D03*
X213385D03*
X203385Y1782520D03*
X213385D03*
X203385Y1957520D03*
Y1946890D03*
X213385Y1957520D03*
Y1946890D03*
X223385Y32520D03*
Y21890D03*
X233385Y32520D03*
Y21890D03*
X243385Y32520D03*
Y21890D03*
X223385Y196890D03*
X233385D03*
X243385D03*
X223385Y207520D03*
X233385D03*
X243385D03*
X223385Y371890D03*
X233385D03*
X243385D03*
X223385Y382520D03*
X233385D03*
X243385D03*
X223386Y557520D03*
Y546890D03*
X233386Y557520D03*
Y546890D03*
X243386Y557520D03*
Y546890D03*
X223386Y732520D03*
Y721890D03*
X233386Y732520D03*
Y721890D03*
X243386Y732520D03*
Y721890D03*
X223385Y896890D03*
X233385D03*
X243385D03*
X223385Y907520D03*
X233385D03*
X243385D03*
X223385Y1071890D03*
X233385D03*
X243385D03*
X223385Y1082520D03*
X233385D03*
X243385D03*
X223385Y1257520D03*
Y1246890D03*
X233385Y1257520D03*
Y1246890D03*
X243385Y1257520D03*
Y1246890D03*
X223385Y1432520D03*
Y1421890D03*
X233385Y1432520D03*
Y1421890D03*
X243385Y1432520D03*
Y1421890D03*
X223385Y1596890D03*
X233385D03*
X243385D03*
X223385Y1607520D03*
X233385D03*
X243385D03*
X223385Y1771890D03*
X233385D03*
X243385D03*
X223385Y1782520D03*
X233385D03*
X243385D03*
X223385Y1957520D03*
Y1946890D03*
X233385Y1957520D03*
Y1946890D03*
X243385Y1957520D03*
Y1946890D03*
X253385Y21890D03*
Y32520D03*
X263385Y21890D03*
Y32520D03*
X253385Y196890D03*
X263385D03*
X253385Y207520D03*
X263385D03*
X253385Y371890D03*
X263385D03*
X253385Y382520D03*
X263385D03*
X253386Y546890D03*
Y557520D03*
X263386Y546890D03*
Y557520D03*
X253386Y721890D03*
Y732520D03*
X263386Y721890D03*
Y732520D03*
X253385Y896890D03*
X263385D03*
X253385Y907520D03*
X263385D03*
X253385Y1071890D03*
X263385D03*
X253385Y1082520D03*
X263385D03*
X253385Y1246890D03*
Y1257520D03*
X263385Y1246890D03*
Y1257520D03*
X253385Y1421890D03*
Y1432520D03*
X263385Y1421890D03*
Y1432520D03*
X253385Y1596890D03*
X263385D03*
X253385Y1607520D03*
X263385D03*
X253385Y1771890D03*
X263385D03*
X253385Y1782520D03*
X263385D03*
X253385Y1946890D03*
Y1957520D03*
X263385Y1946890D03*
Y1957520D03*
X273385Y21890D03*
Y32520D03*
X283385Y21890D03*
Y32520D03*
X273385Y196890D03*
X283385D03*
X273385Y207520D03*
X283385D03*
X273385Y371890D03*
X283385D03*
X273385Y382520D03*
X283385D03*
X273386Y546890D03*
Y557520D03*
X283386Y546890D03*
Y557520D03*
X273386Y721890D03*
Y732520D03*
X283386Y721890D03*
Y732520D03*
X273385Y896890D03*
X283385D03*
X273385Y907520D03*
X283385D03*
X273385Y1071890D03*
X283385D03*
X273385Y1082520D03*
X283385D03*
X273385Y1246890D03*
Y1257520D03*
X283385Y1246890D03*
Y1257520D03*
X273385Y1421890D03*
Y1432520D03*
X283385Y1421890D03*
Y1432520D03*
X273385Y1596890D03*
X283385D03*
X273385Y1607520D03*
X283385D03*
X273385Y1771890D03*
X283385D03*
X273385Y1782520D03*
X283385D03*
X273385Y1946890D03*
Y1957520D03*
X283385Y1946890D03*
Y1957520D03*
X293385Y21890D03*
Y32520D03*
X303385Y21890D03*
Y32520D03*
X313385D03*
Y21890D03*
X293385Y196890D03*
X303385D03*
X313385D03*
X293385Y207520D03*
X303385D03*
X313385D03*
X293385Y371890D03*
X303385D03*
X313385D03*
X293385Y382520D03*
X303385D03*
X313385D03*
X293386Y546890D03*
Y557520D03*
X303386Y546890D03*
Y557520D03*
X313386D03*
Y546890D03*
X293386Y721890D03*
Y732520D03*
X303386Y721890D03*
Y732520D03*
X313386D03*
Y721890D03*
X293385Y896890D03*
X303385D03*
X313385D03*
X293385Y907520D03*
X303385D03*
X313385D03*
X293385Y1071890D03*
X303385D03*
X313385D03*
X293385Y1082520D03*
X303385D03*
X313385D03*
X293385Y1246890D03*
Y1257520D03*
X303385Y1246890D03*
Y1257520D03*
X313385D03*
Y1246890D03*
X293385Y1421890D03*
Y1432520D03*
X303385Y1421890D03*
Y1432520D03*
X313385D03*
Y1421890D03*
X293385Y1596890D03*
X303385D03*
X313385D03*
X293385Y1607520D03*
X303385D03*
X313385D03*
X293385Y1771890D03*
X303385D03*
X313385D03*
X293385Y1782520D03*
X303385D03*
X313385D03*
X293385Y1946890D03*
Y1957520D03*
X303385Y1946890D03*
Y1957520D03*
X313385D03*
Y1946890D03*
X337165Y24705D03*
X323385Y32520D03*
Y21890D03*
X337165Y34705D03*
Y199705D03*
X323385Y196890D03*
X337165Y209705D03*
X323385Y207520D03*
Y371890D03*
X337165Y374705D03*
Y384705D03*
X323385Y382520D03*
X337166Y549705D03*
Y559705D03*
X323386Y557520D03*
Y546890D03*
X337166Y724705D03*
X323386Y732520D03*
Y721890D03*
X337166Y734705D03*
X337165Y899705D03*
X323385Y896890D03*
X337165Y909705D03*
X323385Y907520D03*
Y1071890D03*
X337165Y1074705D03*
Y1084705D03*
X323385Y1082520D03*
X337165Y1249705D03*
Y1259705D03*
X323385Y1257520D03*
Y1246890D03*
X337165Y1424705D03*
Y1434705D03*
X323385Y1432520D03*
Y1421890D03*
X337165Y1599705D03*
X323385Y1596890D03*
X337165Y1609705D03*
X323385Y1607520D03*
Y1771890D03*
X337165Y1774705D03*
Y1784705D03*
X323385Y1782520D03*
X337165Y1949705D03*
Y1959705D03*
X323385Y1957520D03*
Y1946890D03*
X342165Y19705D03*
Y29705D03*
X347165Y24705D03*
X352165Y19705D03*
Y29705D03*
X357165Y24705D03*
X362165Y19705D03*
Y29705D03*
X347165Y34705D03*
X357165D03*
X342165Y194705D03*
X347165Y199705D03*
X352165Y194705D03*
X357165Y199705D03*
X362165Y194705D03*
X342165Y204705D03*
X347165Y209705D03*
X352165Y204705D03*
X357165Y209705D03*
X362165Y204705D03*
X342165Y369705D03*
X352165D03*
X362165D03*
X342165Y379705D03*
X347165Y374705D03*
Y384705D03*
X352165Y379705D03*
X357165Y374705D03*
Y384705D03*
X362165Y379705D03*
X342166Y544705D03*
Y554705D03*
X347166Y549705D03*
Y559705D03*
X352166Y544705D03*
Y554705D03*
X357166Y549705D03*
Y559705D03*
X362166Y544705D03*
Y554705D03*
X342166Y719705D03*
Y729705D03*
X347166Y724705D03*
X352166Y719705D03*
Y729705D03*
X357166Y724705D03*
X362166Y719705D03*
Y729705D03*
X347166Y734705D03*
X357166D03*
X342165Y894705D03*
X347165Y899705D03*
X352165Y894705D03*
X357165Y899705D03*
X362165Y894705D03*
X342165Y904705D03*
X347165Y909705D03*
X352165Y904705D03*
X357165Y909705D03*
X362165Y904705D03*
X342165Y1069705D03*
X352165D03*
X362165D03*
X342165Y1079705D03*
X347165Y1074705D03*
Y1084705D03*
X352165Y1079705D03*
X357165Y1074705D03*
Y1084705D03*
X362165Y1079705D03*
X342165Y1244705D03*
Y1254705D03*
X347165Y1249705D03*
Y1259705D03*
X352165Y1244705D03*
Y1254705D03*
X357165Y1249705D03*
Y1259705D03*
X362165Y1244705D03*
Y1254705D03*
X342165Y1419705D03*
Y1429705D03*
X347165Y1424705D03*
Y1434705D03*
X352165Y1419705D03*
Y1429705D03*
X357165Y1424705D03*
Y1434705D03*
X362165Y1419705D03*
Y1429705D03*
X342165Y1594705D03*
X347165Y1599705D03*
X352165Y1594705D03*
X357165Y1599705D03*
X362165Y1594705D03*
X342165Y1604705D03*
X347165Y1609705D03*
X352165Y1604705D03*
X357165Y1609705D03*
X362165Y1604705D03*
X342165Y1769705D03*
X352165D03*
X362165D03*
X342165Y1779705D03*
X347165Y1774705D03*
Y1784705D03*
X352165Y1779705D03*
X357165Y1774705D03*
Y1784705D03*
X362165Y1779705D03*
X342165Y1944705D03*
Y1954705D03*
X347165Y1949705D03*
Y1959705D03*
X352165Y1944705D03*
Y1954705D03*
X357165Y1949705D03*
Y1959705D03*
X362165Y1944705D03*
Y1954705D03*
G54D34*
X307086Y308267D03*
G54D16*
X20468Y696341D03*
Y984333D03*
X20472Y1054606D03*
Y1342598D03*
G54D25*
X65354Y101180D03*
X55511Y105117D03*
X51574Y114960D03*
X55511Y124803D03*
X65354Y128740D03*
Y451180D03*
X55511Y455117D03*
X51574Y464960D03*
X55511Y474803D03*
X65354Y478740D03*
Y801180D03*
X55511Y805117D03*
X51574Y814960D03*
X55511Y824803D03*
X65354Y828740D03*
Y1151180D03*
X55511Y1155117D03*
X51574Y1164960D03*
X55511Y1174803D03*
X65354Y1178740D03*
Y1501180D03*
X55511Y1505117D03*
X51574Y1514960D03*
X55511Y1524803D03*
X65354Y1528740D03*
Y1851180D03*
X55511Y1855117D03*
X51574Y1864960D03*
X55511Y1874803D03*
X65354Y1878740D03*
X75197Y105117D03*
Y124803D03*
X79134Y114960D03*
Y464960D03*
X75197Y455117D03*
Y474803D03*
Y805117D03*
Y824803D03*
X79134Y814960D03*
Y1164960D03*
X75197Y1155117D03*
Y1174803D03*
Y1505117D03*
Y1524803D03*
X79134Y1514960D03*
Y1864960D03*
X75197Y1855117D03*
Y1874803D03*
X307086Y113385D03*
X297243Y117322D03*
X293306Y127165D03*
X297243Y137008D03*
X307086Y140945D03*
Y463385D03*
X297243Y467322D03*
X293306Y477165D03*
X297243Y487008D03*
X307086Y490945D03*
Y813385D03*
X297243Y817322D03*
X293306Y827165D03*
X297243Y837008D03*
X307086Y840945D03*
Y1329724D03*
X297243Y1333661D03*
X293306Y1343504D03*
X297243Y1353347D03*
X307086Y1357284D03*
Y1679724D03*
X297243Y1683661D03*
X293306Y1693504D03*
X297243Y1703347D03*
X307086Y1707284D03*
X307087Y2029723D03*
X297244Y2033660D03*
X293307Y2043503D03*
X297244Y2053346D03*
X307087Y2057283D03*
X320866Y127165D03*
X316929Y117322D03*
Y137008D03*
Y467322D03*
Y487008D03*
X320866Y477165D03*
Y827165D03*
X316929Y817322D03*
Y837008D03*
Y1333661D03*
Y1353347D03*
X320866Y1343504D03*
Y1693504D03*
X316929Y1683661D03*
Y1703347D03*
X316930Y2033660D03*
Y2053346D03*
X320867Y2043503D03*
G54D26*
X65354Y114960D03*
Y464960D03*
Y814960D03*
Y1164960D03*
Y1514960D03*
Y1864960D03*
X307086Y127165D03*
Y477165D03*
Y827165D03*
Y1343504D03*
Y1693504D03*
X307087Y2043503D03*
G54D35*
X307086Y1883071D03*
G54D17*
X25389Y1030199D03*
X25393Y1388464D03*
G54D36*
X359842Y78780D03*
Y253780D03*
Y428779D03*
Y603779D03*
Y778780D03*
Y953780D03*
Y1128779D03*
Y1303780D03*
Y1478780D03*
Y1653780D03*
Y1828779D03*
Y2003780D03*
G54D27*
X55254Y554500D03*
Y1612504D03*
G54D18*
X23402Y1668874D03*
Y1685410D03*
Y1701945D03*
Y1718480D03*
Y1735016D03*
Y1751551D03*
Y1768087D03*
Y1784622D03*
Y1817693D03*
Y1801158D03*
X45056Y1668874D03*
Y1685410D03*
Y1701945D03*
Y1718480D03*
Y1735016D03*
Y1751551D03*
Y1768087D03*
Y1784622D03*
Y1801158D03*
G54D28*
X55158Y882277D03*
X344826Y2035270D03*
X389572Y66182D03*
G54D37*
X359677Y306891D03*
X362236D03*
Y329891D03*
X359677D03*
X354000Y656986D03*
X356559D03*
X359118D03*
X361677D03*
Y679986D03*
X359118D03*
X356559D03*
X354000D03*
X351983Y1882006D03*
X354542D03*
X357101D03*
X359660D03*
X362219D03*
Y1905006D03*
X359660D03*
X357101D03*
X354542D03*
X351983D03*
X364795Y306891D03*
X367354D03*
X369913D03*
X372472D03*
X375031D03*
Y329891D03*
X372472D03*
X369913D03*
X367354D03*
X364795D03*
X364236Y656986D03*
X366795D03*
X369354D03*
Y679986D03*
X366795D03*
X364236D03*
X372122Y1347255D03*
X374681D03*
X377240D03*
X379799D03*
X382358D03*
X384917D03*
X387476D03*
Y1370255D03*
X384917D03*
X382358D03*
X379799D03*
X377240D03*
X374681D03*
X372122D03*
X364778Y1882006D03*
X367337D03*
Y1905006D03*
X364778D03*
G54D19*
X30473Y102007D03*
Y137440D03*
X30197Y305027D03*
Y352271D03*
X30473Y1855008D03*
Y1890441D03*
Y1937007D03*
Y1972440D03*
Y2012007D03*
Y2047440D03*
G54D38*
X385146Y333689D03*
Y330539D03*
X380915Y333668D03*
Y330518D03*
G54D29*
X119920Y18071D03*
Y28071D03*
Y38071D03*
Y48071D03*
Y58071D03*
Y68071D03*
Y78071D03*
Y88071D03*
Y98071D03*
Y108071D03*
Y118071D03*
Y128071D03*
Y138071D03*
Y148071D03*
Y158071D03*
Y168071D03*
Y178071D03*
Y188071D03*
Y198071D03*
Y208071D03*
Y218071D03*
Y228071D03*
Y238071D03*
Y248071D03*
Y258071D03*
Y268071D03*
Y278071D03*
Y288071D03*
Y298071D03*
Y308071D03*
Y318071D03*
Y366102D03*
Y376102D03*
Y386102D03*
Y396102D03*
Y406102D03*
Y416102D03*
Y426102D03*
Y436102D03*
Y446102D03*
Y456102D03*
Y466102D03*
Y476102D03*
Y486102D03*
Y496102D03*
Y506102D03*
Y516102D03*
Y526102D03*
Y536102D03*
Y546102D03*
Y556102D03*
Y566102D03*
Y576102D03*
Y586102D03*
Y596102D03*
Y606102D03*
Y616102D03*
Y626102D03*
Y636102D03*
Y646102D03*
Y656102D03*
Y666102D03*
Y714134D03*
Y724134D03*
Y734134D03*
Y744134D03*
Y754134D03*
Y764134D03*
Y774134D03*
Y784134D03*
Y794134D03*
Y804134D03*
Y814134D03*
Y824134D03*
Y834134D03*
Y844134D03*
Y854134D03*
Y864134D03*
Y874134D03*
Y884134D03*
Y894134D03*
Y904134D03*
Y914134D03*
Y924134D03*
Y934134D03*
Y944134D03*
Y954134D03*
Y964134D03*
Y974134D03*
Y984134D03*
Y994134D03*
Y1004134D03*
Y1014134D03*
Y1062165D03*
Y1072165D03*
Y1082165D03*
Y1092165D03*
Y1102165D03*
Y1112165D03*
Y1122165D03*
Y1132165D03*
Y1142165D03*
Y1152165D03*
Y1162165D03*
Y1172165D03*
Y1182165D03*
Y1192165D03*
Y1202165D03*
Y1212165D03*
Y1222165D03*
Y1232165D03*
Y1242165D03*
Y1252165D03*
Y1262165D03*
Y1272165D03*
Y1282165D03*
Y1292165D03*
Y1302165D03*
Y1312165D03*
Y1322165D03*
Y1332165D03*
Y1342165D03*
Y1352165D03*
Y1362165D03*
Y1410197D03*
Y1420197D03*
Y1430197D03*
Y1440197D03*
Y1450197D03*
Y1460197D03*
Y1470197D03*
Y1480197D03*
Y1490197D03*
Y1500197D03*
Y1510197D03*
Y1520197D03*
Y1530197D03*
Y1540197D03*
Y1550197D03*
Y1560197D03*
Y1570197D03*
Y1580197D03*
Y1590197D03*
Y1600197D03*
Y1610197D03*
Y1620197D03*
Y1630197D03*
Y1640197D03*
Y1650197D03*
Y1660197D03*
Y1670197D03*
Y1680197D03*
Y1690197D03*
Y1700197D03*
Y1710197D03*
Y1758228D03*
Y1768228D03*
Y1778228D03*
Y1788228D03*
Y1798228D03*
Y1808228D03*
Y1818228D03*
Y1828228D03*
Y1838228D03*
Y1848228D03*
Y1858228D03*
Y1868228D03*
Y1878228D03*
Y1888228D03*
Y1898228D03*
Y1908228D03*
Y1918228D03*
Y1928228D03*
Y1938228D03*
Y1948228D03*
Y1958228D03*
Y1968228D03*
Y1978228D03*
Y1988228D03*
Y1998228D03*
Y2008228D03*
Y2018228D03*
Y2028228D03*
Y2038228D03*
Y2048228D03*
Y2058228D03*
X139920Y28071D03*
Y18071D03*
Y58071D03*
Y48071D03*
Y38071D03*
Y78071D03*
Y68071D03*
Y98071D03*
Y88071D03*
Y128071D03*
Y118071D03*
Y108071D03*
Y148071D03*
Y138071D03*
Y178071D03*
Y168071D03*
Y158071D03*
Y198071D03*
Y188071D03*
Y228071D03*
Y218071D03*
Y208071D03*
Y248071D03*
Y238071D03*
Y268071D03*
Y258071D03*
Y298071D03*
Y288071D03*
Y278071D03*
Y318071D03*
Y308071D03*
Y328071D03*
Y366102D03*
Y396102D03*
Y386102D03*
Y376102D03*
Y416102D03*
Y406102D03*
Y436102D03*
Y426102D03*
Y466102D03*
Y456102D03*
Y446102D03*
Y486102D03*
Y476102D03*
Y516102D03*
Y506102D03*
Y496102D03*
Y536102D03*
Y526102D03*
Y566102D03*
Y556102D03*
Y546102D03*
Y586102D03*
Y576102D03*
Y606102D03*
Y596102D03*
Y636102D03*
Y626102D03*
Y616102D03*
Y656102D03*
Y646102D03*
Y676102D03*
Y666102D03*
Y734134D03*
Y724134D03*
Y714134D03*
Y754134D03*
Y744134D03*
Y774134D03*
Y764134D03*
Y804134D03*
Y794134D03*
Y784134D03*
Y824134D03*
Y814134D03*
Y854134D03*
Y844134D03*
Y834134D03*
Y874134D03*
Y864134D03*
Y904134D03*
Y894134D03*
Y884134D03*
Y924134D03*
Y914134D03*
Y944134D03*
Y934134D03*
Y974134D03*
Y964134D03*
Y954134D03*
Y994134D03*
Y984134D03*
Y1024134D03*
Y1014134D03*
Y1004134D03*
Y1072165D03*
Y1062165D03*
Y1092165D03*
Y1082165D03*
Y1122165D03*
Y1112165D03*
Y1102165D03*
Y1142165D03*
Y1132165D03*
Y1162165D03*
Y1152165D03*
Y1192165D03*
Y1182165D03*
Y1172165D03*
Y1212165D03*
Y1202165D03*
Y1242165D03*
Y1232165D03*
Y1222165D03*
Y1262165D03*
Y1252165D03*
Y1282165D03*
Y1272165D03*
Y1312165D03*
Y1302165D03*
Y1292165D03*
Y1332165D03*
Y1322165D03*
Y1362165D03*
Y1352165D03*
Y1342165D03*
Y1372165D03*
Y1410197D03*
Y1430197D03*
Y1420197D03*
Y1460197D03*
Y1450197D03*
Y1440197D03*
Y1480197D03*
Y1470197D03*
Y1500197D03*
Y1490197D03*
Y1530197D03*
Y1520197D03*
Y1510197D03*
Y1550197D03*
Y1540197D03*
Y1580197D03*
Y1570197D03*
Y1560197D03*
Y1600197D03*
Y1590197D03*
Y1620197D03*
Y1610197D03*
Y1650197D03*
Y1640197D03*
Y1630197D03*
Y1670197D03*
Y1660197D03*
Y1700197D03*
Y1690197D03*
Y1680197D03*
Y1720197D03*
Y1710197D03*
Y1768228D03*
Y1758228D03*
Y1798228D03*
Y1788228D03*
Y1778228D03*
Y1818228D03*
Y1808228D03*
Y1838228D03*
Y1828228D03*
Y1868228D03*
Y1858228D03*
Y1848228D03*
Y1888228D03*
Y1878228D03*
Y1918228D03*
Y1908228D03*
Y1898228D03*
Y1938228D03*
Y1928228D03*
Y1958228D03*
Y1948228D03*
Y1988228D03*
Y1978228D03*
Y1968228D03*
Y2008228D03*
Y1998228D03*
Y2038228D03*
Y2028228D03*
Y2018228D03*
Y2058228D03*
Y2048228D03*
Y2068228D03*
G54D39*
X379000Y672905D03*
X375850D03*
X384867Y1377774D03*
X388017D03*
X381927Y1901748D03*
X378777D03*
M02*
